(kicad_pcb
	(version 20260206)
	(generator "pcbnew")
	(generator_version "10.0")
	(general
		(thickness 1.6)
		(legacy_teardrops no)
	)
	(paper "A4")
	(title_block
		(title "v1-pdb — T6M_PDB_D_0927_0900.brd")
		(comment 1 "Open CloudServer (Microsoft) / footprints 19-26 of 321")
	)
	(layers
		(0 "F.Cu" signal "TOP")
		(4 "In1.Cu" signal "GND")
		(6 "In2.Cu" signal "IN1")
		(8 "In3.Cu" signal "VCC")
		(10 "In4.Cu" signal "VCC1")
		(12 "In5.Cu" signal "IN2")
		(14 "In6.Cu" signal "GND1")
		(2 "B.Cu" signal "BOTTOM")
		(9 "F.Adhes" user "F.Adhesive")
		(11 "B.Adhes" user "B.Adhesive")
		(13 "F.Paste" user "Package Geometry/Pastemask Top")
		(15 "B.Paste" user "Package Geometry/Pastemask Bottom")
		(5 "F.SilkS" user "Ref Des/Silkscreen Top")
		(7 "B.SilkS" user "Ref Des/Silkscreen Bottom")
		(1 "F.Mask" user "Board Geometry/Soldermask Top")
		(3 "B.Mask" user "Board Geometry/Soldermask Bottom")
		(17 "Dwgs.User" user "User.Drawings")
		(19 "Cmts.User" user "User.Comments")
		(21 "Eco1.User" user "User.Eco1")
		(23 "Eco2.User" user "User.Eco2")
		(25 "Edge.Cuts" user "Board Geometry/Outline")
		(27 "Margin" user)
		(31 "F.CrtYd" user "Package Geometry/Place Bound Top")
		(29 "B.CrtYd" user "Package Geometry/Place Bound Bottom")
		(35 "F.Fab" user "Ref Des/Assembly Top")
		(33 "B.Fab" user "Ref Des/Assembly Bottom")
	)
	(footprint ""
		(layer "F.Cu")
		(at 16.599916 -29.19984)
		(property "Reference" "H11"
			(at 6.04139 -6.838696 0)
			(unlocked yes)
			(layer "F.SilkS")
			(effects
				(font
					(size 0.7874 0.5842)
					(thickness 0.1524)
				)
				(justify left)
			)
		)
		(property "Value" ""
			(at 0 0 0)
			(layer "F.Fab")
			(effects
				(font
					(size 1.27 1.27)
				)
			)
		)
		(duplicate_pad_numbers_are_jumpers no)
		(fp_circle
			(center 0 0)
			(end 7.999984 0)
			(stroke
				(width 0.1524)
				(type default)
			)
			(fill no)
			(layer "F.SilkS")
		)
		(fp_circle
			(center 0 0)
			(end 14.7066 0)
			(stroke
				(width 0.1524)
				(type default)
			)
			(fill no)
			(layer "B.SilkS")
		)
		(fp_poly
			(pts
				(arc
					(start 0 5.0038)
					(mid 0 -5.0038)
					(end 0 5.0038)
				)
			)
			(stroke
				(width 0)
				(type default)
			)
			(fill no)
			(layer "F.CrtYd")
		)
		(pad "" np_thru_hole circle
			(at 0 0)
			(size 4.0132 4.0132)
			(drill 4.0132)
			(layers "*.Cu" "*.Mask")
			(clearance 0.381)
			(thermal_gap 0.381)
		)
		(pad "2" thru_hole circle
			(at 0 -3.50012)
			(size 0.762 0.762)
			(drill 0.5588)
			(layers "*.Cu" "*.Mask")
			(remove_unused_layers no)
			(net "GND")
			(clearance 0.1524)
			(thermal_gap 0.1524)
		)
		(pad "3" thru_hole circle
			(at -2.500122 -2.500122)
			(size 0.762 0.762)
			(drill 0.5588)
			(layers "*.Cu" "*.Mask")
			(remove_unused_layers no)
			(net "GND")
			(clearance 0.1524)
			(thermal_gap 0.1524)
		)
		(pad "4" thru_hole circle
			(at -3.50012 0)
			(size 0.762 0.762)
			(drill 0.5588)
			(layers "*.Cu" "*.Mask")
			(remove_unused_layers no)
			(net "GND")
			(clearance 0.1524)
			(thermal_gap 0.1524)
		)
		(pad "5" thru_hole circle
			(at -2.500122 2.500122)
			(size 0.762 0.762)
			(drill 0.5588)
			(layers "*.Cu" "*.Mask")
			(remove_unused_layers no)
			(net "GND")
			(clearance 0.1524)
			(thermal_gap 0.1524)
		)
		(pad "6" thru_hole circle
			(at 0 3.50012)
			(size 0.762 0.762)
			(drill 0.5588)
			(layers "*.Cu" "*.Mask")
			(remove_unused_layers no)
			(net "GND")
			(clearance 0.1524)
			(thermal_gap 0.1524)
		)
		(pad "7" thru_hole circle
			(at 2.500122 2.500122)
			(size 0.762 0.762)
			(drill 0.5588)
			(layers "*.Cu" "*.Mask")
			(remove_unused_layers no)
			(net "GND")
			(clearance 0.1524)
			(thermal_gap 0.1524)
		)
		(pad "8" thru_hole circle
			(at 3.50012 0)
			(size 0.762 0.762)
			(drill 0.5588)
			(layers "*.Cu" "*.Mask")
			(remove_unused_layers no)
			(net "GND")
			(clearance 0.1524)
			(thermal_gap 0.1524)
		)
		(pad "9" thru_hole circle
			(at 2.500122 -2.500122)
			(size 0.762 0.762)
			(drill 0.5588)
			(layers "*.Cu" "*.Mask")
			(remove_unused_layers no)
			(net "GND")
			(clearance 0.1524)
			(thermal_gap 0.1524)
		)
		(zone
			(layer "F.Cu")
			(hatch none 0.5)
			(connect_pads
				(clearance 0)
			)
			(min_thickness 0.25)
			(keepout
				(tracks not_allowed)
				(vias allowed)
				(pads allowed)
				(copperpour not_allowed)
				(footprints allowed)
			)
			(placement
				(enabled no)
				(sheetname "")
			)
			(fill
				(thermal_gap 0.5)
				(thermal_bridge_width 0.5)
				(island_removal_mode 0)
			)
			(polygon
				(pts
					(arc
						(start 16.599916 -37.20084)
						(mid 8.598916 -29.19984)
						(end 16.599916 -21.19884)
					)
					(arc
						(start 16.599916 -21.19884)
						(mid 18.035016 -22.63394)
						(end 16.599916 -24.06904)
					)
					(arc
						(start 16.599916 -24.06904)
						(mid 11.469116 -29.19984)
						(end 16.599916 -34.33064)
					)
					(arc
						(start 16.599916 -34.33064)
						(mid 18.035016 -35.76574)
						(end 16.599916 -37.20084)
					)
				)
			)
		)
		(zone
			(layer "F.Cu")
			(hatch none 0.5)
			(connect_pads
				(clearance 0)
			)
			(min_thickness 0.25)
			(keepout
				(tracks not_allowed)
				(vias allowed)
				(pads allowed)
				(copperpour not_allowed)
				(footprints allowed)
			)
			(placement
				(enabled no)
				(sheetname "")
			)
			(fill
				(thermal_gap 0.5)
				(thermal_bridge_width 0.5)
				(island_removal_mode 0)
			)
			(polygon
				(pts
					(arc
						(start 16.599916 -37.20084)
						(mid 24.600916 -29.19984)
						(end 16.599916 -21.19884)
					)
					(arc
						(start 16.599916 -21.19884)
						(mid 15.164816 -22.63394)
						(end 16.599916 -24.06904)
					)
					(arc
						(start 16.599916 -24.06904)
						(mid 21.730716 -29.19984)
						(end 16.599916 -34.33064)
					)
					(arc
						(start 16.599916 -34.33064)
						(mid 15.164816 -35.76574)
						(end 16.599916 -37.20084)
					)
				)
			)
		)
		(zone
			(layers "F.Cu" "B.Cu" "In1.Cu" "In2.Cu" "In3.Cu" "In4.Cu" "In5.Cu" "In6.Cu")
			(hatch none 0.5)
			(connect_pads
				(clearance 0)
			)
			(min_thickness 0.25)
			(keepout
				(tracks not_allowed)
				(vias allowed)
				(pads allowed)
				(copperpour not_allowed)
				(footprints allowed)
			)
			(placement
				(enabled no)
				(sheetname "")
			)
			(fill
				(thermal_gap 0.5)
				(thermal_bridge_width 0.5)
				(island_removal_mode 0)
			)
			(polygon
				(pts
					(arc
						(start 16.599916 -26.68778)
						(mid 16.599916 -31.7119)
						(end 16.599916 -26.68778)
					)
				)
			)
		)
	)
	(footprint ""
		(layer "F.Cu")
		(at 39.46398 -22.785324 -90)
		(property "Reference" "R86"
			(at -1.022858 -0.025146 90)
			(unlocked yes)
			(layer "F.SilkS")
			(effects
				(font
					(size 0.7874 0.5842)
					(thickness 0.1524)
				)
				(justify left)
			)
		)
		(property "Value" ""
			(at 0 0 270)
			(layer "F.Fab")
			(effects
				(font
					(size 1.27 1.27)
				)
			)
		)
		(duplicate_pad_numbers_are_jumpers no)
		(fp_line
			(start -0.7874 0.4064)
			(end -0.7874 -0.4064)
			(stroke
				(width 0.1524)
				(type default)
			)
			(layer "F.SilkS")
		)
		(fp_line
			(start 0.7874 0.4064)
			(end -0.7874 0.4064)
			(stroke
				(width 0.1524)
				(type default)
			)
			(layer "F.SilkS")
		)
		(fp_line
			(start -0.7874 -0.4064)
			(end 0.7874 -0.4064)
			(stroke
				(width 0.1524)
				(type default)
			)
			(layer "F.SilkS")
		)
		(fp_line
			(start 0.7874 -0.4064)
			(end 0.7874 0.4064)
			(stroke
				(width 0.1524)
				(type default)
			)
			(layer "F.SilkS")
		)
		(fp_poly
			(pts
				(xy -0.508 0.2794) (xy -0.508 0.2286) (xy -0.635 0.2286) (xy -0.635 -0.254) (xy -0.5334 -0.254)
				(xy -0.5334 -0.2794) (xy 0.5334 -0.2794) (xy 0.5334 -0.254) (xy 0.635 -0.254) (xy 0.635 0.254) (xy 0.5334 0.254)
				(xy 0.5334 0.2794)
			)
			(stroke
				(width 0)
				(type default)
			)
			(fill no)
			(layer "F.CrtYd")
		)
		(pad "1" smd rect
			(at 0.40005 0 270)
			(size 0.4572 0.508)
			(layers "F.Cu" "F.Mask" "F.Paste")
			(net "PSU1_REMOTE_P")
		)
		(pad "2" smd rect
			(at -0.40005 0 270)
			(size 0.4572 0.508)
			(layers "F.Cu" "F.Mask" "F.Paste")
			(net "PSU1_REMOTE_R_P")
		)
	)
	(footprint ""
		(layer "F.Cu")
		(at 72.81291 -104.75976 -90)
		(property "Reference" "C16"
			(at -2.68224 0.11684 90)
			(unlocked yes)
			(layer "F.SilkS")
			(effects
				(font
					(size 0.7874 0.5842)
					(thickness 0.1524)
				)
				(justify left)
			)
		)
		(property "Value" ""
			(at 0 0 270)
			(layer "F.Fab")
			(effects
				(font
					(size 1.27 1.27)
				)
			)
		)
		(duplicate_pad_numbers_are_jumpers no)
		(fp_line
			(start -0.7874 0.4064)
			(end -0.7874 -0.4064)
			(stroke
				(width 0.1524)
				(type default)
			)
			(layer "F.SilkS")
		)
		(fp_line
			(start 0.7874 0.4064)
			(end -0.7874 0.4064)
			(stroke
				(width 0.1524)
				(type default)
			)
			(layer "F.SilkS")
		)
		(fp_line
			(start 0 0.381)
			(end 0 -0.381)
			(stroke
				(width 0.1524)
				(type default)
			)
			(layer "F.SilkS")
		)
		(fp_line
			(start -0.7874 -0.4064)
			(end 0.7874 -0.4064)
			(stroke
				(width 0.1524)
				(type default)
			)
			(layer "F.SilkS")
		)
		(fp_line
			(start 0.7874 -0.4064)
			(end 0.7874 0.4064)
			(stroke
				(width 0.1524)
				(type default)
			)
			(layer "F.SilkS")
		)
		(fp_poly
			(pts
				(xy -0.5334 0.254) (xy -0.635 0.254) (xy -0.635 0.2286) (xy -0.635 -0.254) (xy -0.5334 -0.254) (xy -0.5334 -0.2794)
				(xy 0.5334 -0.2794) (xy 0.5334 -0.254) (xy 0.635 -0.254) (xy 0.635 0.254) (xy 0.5334 0.254) (xy 0.5334 0.2794)
				(xy -0.508 0.2794) (xy -0.5334 0.2794)
			)
			(stroke
				(width 0)
				(type default)
			)
			(fill no)
			(layer "F.CrtYd")
		)
		(pad "1" smd rect
			(at 0.40005 0 270)
			(size 0.4572 0.508)
			(layers "F.Cu" "F.Mask" "F.Paste")
			(net "P12V")
		)
		(pad "2" smd rect
			(at -0.40005 0 270)
			(size 0.4572 0.508)
			(layers "F.Cu" "F.Mask" "F.Paste")
			(net "GND")
		)
	)
	(footprint ""
		(layer "F.Cu")
		(at 13.386308 -319.438782 180)
		(property "Reference" "R141"
			(at -1.21285 -0.090678 0)
			(unlocked yes)
			(layer "F.SilkS")
			(effects
				(font
					(size 0.7874 0.5842)
					(thickness 0.1524)
				)
				(justify left)
			)
		)
		(property "Value" ""
			(at 0 0 180)
			(layer "F.Fab")
			(effects
				(font
					(size 1.27 1.27)
				)
			)
		)
		(duplicate_pad_numbers_are_jumpers no)
		(fp_line
			(start 0.7874 0.4064)
			(end -0.7874 0.4064)
			(stroke
				(width 0.1524)
				(type default)
			)
			(layer "F.SilkS")
		)
		(fp_line
			(start 0.7874 -0.4064)
			(end 0.7874 0.4064)
			(stroke
				(width 0.1524)
				(type default)
			)
			(layer "F.SilkS")
		)
		(fp_line
			(start -0.7874 0.4064)
			(end -0.7874 -0.4064)
			(stroke
				(width 0.1524)
				(type default)
			)
			(layer "F.SilkS")
		)
		(fp_line
			(start -0.7874 -0.4064)
			(end 0.7874 -0.4064)
			(stroke
				(width 0.1524)
				(type default)
			)
			(layer "F.SilkS")
		)
		(fp_poly
			(pts
				(xy -0.508 0.2794) (xy -0.508 0.2286) (xy -0.635 0.2286) (xy -0.635 -0.254) (xy -0.5334 -0.254)
				(xy -0.5334 -0.2794) (xy 0.5334 -0.2794) (xy 0.5334 -0.254) (xy 0.635 -0.254) (xy 0.635 0.254) (xy 0.5334 0.254)
				(xy 0.5334 0.2794)
			)
			(stroke
				(width 0)
				(type default)
			)
			(fill no)
			(layer "F.CrtYd")
		)
		(pad "1" smd rect
			(at 0.40005 0 180)
			(size 0.4572 0.508)
			(layers "F.Cu" "F.Mask" "F.Paste")
			(net "FAN_PWM")
		)
		(pad "2" smd rect
			(at -0.40005 0 180)
			(size 0.4572 0.508)
			(layers "F.Cu" "F.Mask" "F.Paste")
			(net "P12V")
		)
	)
	(footprint ""
		(layer "F.Cu")
		(at 46.408086 -239.669066 180)
		(property "Reference" "R89"
			(at 4.341114 0.123698 0)
			(unlocked yes)
			(layer "F.SilkS")
			(effects
				(font
					(size 0.7874 0.5842)
					(thickness 0.1524)
				)
				(justify left)
			)
		)
		(property "Value" ""
			(at 0 0 180)
			(layer "F.Fab")
			(effects
				(font
					(size 1.27 1.27)
				)
			)
		)
		(duplicate_pad_numbers_are_jumpers no)
		(fp_line
			(start 0.7874 0.4064)
			(end -0.7874 0.4064)
			(stroke
				(width 0.1524)
				(type default)
			)
			(layer "F.SilkS")
		)
		(fp_line
			(start 0.7874 -0.4064)
			(end 0.7874 0.4064)
			(stroke
				(width 0.1524)
				(type default)
			)
			(layer "F.SilkS")
		)
		(fp_line
			(start -0.7874 0.4064)
			(end -0.7874 -0.4064)
			(stroke
				(width 0.1524)
				(type default)
			)
			(layer "F.SilkS")
		)
		(fp_line
			(start -0.7874 -0.4064)
			(end 0.7874 -0.4064)
			(stroke
				(width 0.1524)
				(type default)
			)
			(layer "F.SilkS")
		)
		(fp_poly
			(pts
				(xy -0.508 0.2794) (xy -0.508 0.2286) (xy -0.635 0.2286) (xy -0.635 -0.254) (xy -0.5334 -0.254)
				(xy -0.5334 -0.2794) (xy 0.5334 -0.2794) (xy 0.5334 -0.254) (xy 0.635 -0.254) (xy 0.635 0.254) (xy 0.5334 0.254)
				(xy 0.5334 0.2794)
			)
			(stroke
				(width 0)
				(type default)
			)
			(fill no)
			(layer "F.CrtYd")
		)
		(pad "1" smd rect
			(at 0.40005 0 180)
			(size 0.4572 0.508)
			(layers "F.Cu" "F.Mask" "F.Paste")
			(net "PSU1_REMOTE_R_N")
		)
		(pad "2" smd rect
			(at -0.40005 0 180)
			(size 0.4572 0.508)
			(layers "F.Cu" "F.Mask" "F.Paste")
			(net "GND")
		)
	)
	(footprint ""
		(layer "F.Cu")
		(at 39.436802 -287.17748 90)
		(property "Reference" "R122"
			(at -3.06705 1.662938 90)
			(unlocked yes)
			(layer "F.SilkS")
			(effects
				(font
					(size 0.7874 0.5842)
					(thickness 0.1524)
				)
				(justify left)
			)
		)
		(property "Value" ""
			(at 0 0 90)
			(layer "F.Fab")
			(effects
				(font
					(size 1.27 1.27)
				)
			)
		)
		(duplicate_pad_numbers_are_jumpers no)
		(fp_line
			(start 0.7874 -0.4064)
			(end 0.7874 0.4064)
			(stroke
				(width 0.1524)
				(type default)
			)
			(layer "F.SilkS")
		)
		(fp_line
			(start -0.7874 -0.4064)
			(end 0.7874 -0.4064)
			(stroke
				(width 0.1524)
				(type default)
			)
			(layer "F.SilkS")
		)
		(fp_line
			(start 0.7874 0.4064)
			(end -0.7874 0.4064)
			(stroke
				(width 0.1524)
				(type default)
			)
			(layer "F.SilkS")
		)
		(fp_line
			(start -0.7874 0.4064)
			(end -0.7874 -0.4064)
			(stroke
				(width 0.1524)
				(type default)
			)
			(layer "F.SilkS")
		)
		(fp_poly
			(pts
				(xy -0.508 0.2794) (xy -0.508 0.2286) (xy -0.635 0.2286) (xy -0.635 -0.254) (xy -0.5334 -0.254)
				(xy -0.5334 -0.2794) (xy 0.5334 -0.2794) (xy 0.5334 -0.254) (xy 0.635 -0.254) (xy 0.635 0.254) (xy 0.5334 0.254)
				(xy 0.5334 0.2794)
			)
			(stroke
				(width 0)
				(type default)
			)
			(fill no)
			(layer "F.CrtYd")
		)
		(pad "1" smd rect
			(at 0.40005 0 90)
			(size 0.4572 0.508)
			(layers "F.Cu" "F.Mask" "F.Paste")
			(net "PSU4_REMOTE_P")
		)
		(pad "2" smd rect
			(at -0.40005 0 90)
			(size 0.4572 0.508)
			(layers "F.Cu" "F.Mask" "F.Paste")
			(net "PSU4_REMOTE_R2_P")
		)
	)
	(footprint ""
		(layer "F.Cu")
		(at 50.150522 -128.655318 180)
		(property "Reference" "CE6"
			(at 0.794004 -5.521452 0)
			(unlocked yes)
			(layer "F.SilkS")
			(effects
				(font
					(size 0.7874 0.5842)
					(thickness 0.1524)
				)
				(justify left)
			)
		)
		(property "Value" ""
			(at 0 0 180)
			(layer "F.Fab")
			(effects
				(font
					(size 1.27 1.27)
				)
			)
		)
		(duplicate_pad_numbers_are_jumpers no)
		(fp_line
			(start 0 -4.2672)
			(end 0 4.2672)
			(stroke
				(width 0.1524)
				(type default)
			)
			(layer "F.SilkS")
		)
		(fp_circle
			(center 0 0)
			(end -4.2672 0)
			(stroke
				(width 0.1524)
				(type default)
			)
			(fill no)
			(layer "F.SilkS")
		)
		(fp_poly
			(pts
				(arc
					(start 0 -4.2672)
					(mid 4.2672 0)
					(end 0 4.2672)
				)
			)
			(stroke
				(width 0)
				(type default)
			)
			(fill yes)
			(layer "F.SilkS")
		)
		(fp_poly
			(pts
				(xy -2.5146 -0.762) (xy -0.9906 -0.762) (xy -0.9906 0.762) (xy -2.5146 0.762)
			)
			(stroke
				(width 0)
				(type default)
			)
			(fill no)
			(layer "B.CrtYd")
		)
		(fp_poly
			(pts
				(arc
					(start 1.7526 0.762)
					(mid 2.291415 -0.538815)
					(end 0.9906 0)
				)
				(arc
					(start 0.9906 0.0254)
					(mid 1.206345 0.546255)
					(end 1.7272 0.762)
				)
			)
			(stroke
				(width 0)
				(type default)
			)
			(fill no)
			(layer "B.CrtYd")
		)
		(fp_poly
			(pts
				(arc
					(start -4.2672 0)
					(mid 4.2672 0)
					(end -4.2672 0)
				)
			)
			(stroke
				(width 0)
				(type default)
			)
			(fill no)
			(layer "F.CrtYd")
		)
		(fp_circle
			(center 0 0)
			(end -4.2672 0)
			(stroke
				(width 0.1)
				(type default)
			)
			(fill no)
			(layer "F.Fab")
		)
		(fp_text user "+"
			(at -4.720082 -1.919224 180)
			(unlocked yes)
			(layer "F.SilkS")
			(effects
				(font
					(size 0.7874 0.5842)
					(thickness 0.1524)
				)
				(justify left)
			)
		)
		(fp_text user "+"
			(at -5.6642 -0.34925 180)
			(unlocked yes)
			(layer "F.Fab")
			(effects
				(font
					(size 1.905 1.4224)
					(thickness 0.000001)
				)
				(justify left)
			)
		)
		(pad "1" thru_hole rect
			(at -1.75006 0 180)
			(size 1.397 1.397)
			(drill 0.9144)
			(layers "*.Cu" "*.Mask")
			(remove_unused_layers no)
			(net "P12V")
			(clearance 0.0127)
			(thermal_gap 0.0127)
			(padstack
				(mode front_inner_back)
				(layer "Inner"
					(shape circle)
					(size 1.397 1.397)
					(clearance 0.0127)
				)
				(layer "B.Cu"
					(shape rect)
					(size 1.397 1.397)
					(clearance 0.0127)
				)
			)
		)
		(pad "2" thru_hole circle
			(at 1.75006 0 180)
			(size 1.397 1.397)
			(drill 0.9144)
			(layers "*.Cu" "*.Mask")
			(remove_unused_layers no)
			(net "GND")
			(clearance 0.0127)
			(thermal_gap 0.0127)
		)
	)
	(footprint ""
		(layer "F.Cu")
		(at 27.243786 -285.030164)
		(property "Reference" "R20"
			(at -3.418332 0.009144 0)
			(unlocked yes)
			(layer "F.SilkS")
			(effects
				(font
					(size 0.7874 0.5842)
					(thickness 0.1524)
				)
				(justify left)
			)
		)
		(property "Value" ""
			(at 0 0 0)
			(layer "F.Fab")
			(effects
				(font
					(size 1.27 1.27)
				)
			)
		)
		(duplicate_pad_numbers_are_jumpers no)
		(fp_line
			(start -0.7874 -0.4064)
			(end 0.7874 -0.4064)
			(stroke
				(width 0.1524)
				(type default)
			)
			(layer "F.SilkS")
		)
		(fp_line
			(start -0.7874 0.4064)
			(end -0.7874 -0.4064)
			(stroke
				(width 0.1524)
				(type default)
			)
			(layer "F.SilkS")
		)
		(fp_line
			(start 0.7874 -0.4064)
			(end 0.7874 0.4064)
			(stroke
				(width 0.1524)
				(type default)
			)
			(layer "F.SilkS")
		)
		(fp_line
			(start 0.7874 0.4064)
			(end -0.7874 0.4064)
			(stroke
				(width 0.1524)
				(type default)
			)
			(layer "F.SilkS")
		)
		(fp_poly
			(pts
				(xy -0.508 0.2794) (xy -0.508 0.2286) (xy -0.635 0.2286) (xy -0.635 -0.254) (xy -0.5334 -0.254)
				(xy -0.5334 -0.2794) (xy 0.5334 -0.2794) (xy 0.5334 -0.254) (xy 0.635 -0.254) (xy 0.635 0.254) (xy 0.5334 0.254)
				(xy 0.5334 0.2794)
			)
			(stroke
				(width 0)
				(type default)
			)
			(fill no)
			(layer "F.CrtYd")
		)
		(pad "1" smd rect
			(at 0.40005 0)
			(size 0.4572 0.508)
			(layers "F.Cu" "F.Mask" "F.Paste")
			(net "PSU4_REMOTE_N")
		)
		(pad "2" smd rect
			(at -0.40005 0)
			(size 0.4572 0.508)
			(layers "F.Cu" "F.Mask" "F.Paste")
			(net "GND")
		)
	)
)
